# T6G (Grand Teton) — schematic netlist excerpt (pin names and nets, part order shuffled) for the footprints in the layout excerpt that follows; sources: Cadence DE-HDL packaged netlist, KiCad conversion of 04192023_DAF0TMB3IC0_F0TG_MB_C_brd_V02_OCP.brd

U265  ISL28022FRZT  ISL28022FRZ-T IC  pkg QFN16_TH_0-5_3X3XH  page 237
  A1  = INA230_5_A1
  A0  = INA230_5_A0
  \ext_clk||int\  = P12V_SCM_ADC_ALERT_R
  \sda||smbdat\  = SMB_INA230_5_3V3AUX_SDA_R1
  \scl|||smbclk\  = SMB_INA230_5_3V3AUX_SCL_R1
  NC0  = NC_INA230_5_NC0
  NC1  = NC_INA230_5_NC1
  NC2  = NC_INA230_5_NC2
  VCC  = P3V3_AUX
  GND  = GND
  VBUS  = P12V_SCM_R
  VINM  = VSENSE_P12V_INA230_5_INN
  VINP  = VSENSE_P12V_INA230_5_INP
  NC3  = NC_INA230_5_NC3
  NC4  = NC_INA230_5_NC4
  NC5  = NC_INA230_5_NC5
  TH_GND  = GND

(kicad_pcb
	(version 20260206)
	(generator "pcbnew")
	(generator_version "10.0")
	(general
		(thickness 1.6)
		(legacy_teardrops no)
	)
	(paper "A4")
	(title_block
		(title "04192023_DAF0TMB3IC0_F0TG_MB_C_brd_V02_OCP.brd")
		(comment 1 "Grand Teton / footprints 2696-2696 of 8354")
	)
	(layers
		(0 "F.Cu" signal "TOP")
		(4 "In1.Cu" signal "GND")
		(6 "In2.Cu" signal "IN1")
		(8 "In3.Cu" signal "GND1")
		(10 "In4.Cu" signal "IN2")
		(12 "In5.Cu" signal "GND2")
		(14 "In6.Cu" signal "IN3")
		(16 "In7.Cu" signal "GND3")
		(18 "In8.Cu" signal "VCC")
		(20 "In9.Cu" signal "VCC1")
		(22 "In10.Cu" signal "GND4")
		(24 "In11.Cu" signal "IN4")
		(26 "In12.Cu" signal "GND5")
		(28 "In13.Cu" signal "IN5")
		(30 "In14.Cu" signal "GND6")
		(32 "In15.Cu" signal "IN6")
		(34 "In16.Cu" signal "GND7")
		(2 "B.Cu" signal "BOTTOM")
		(9 "F.Adhes" user "F.Adhesive")
		(11 "B.Adhes" user "B.Adhesive")
		(13 "F.Paste" user "Package Geometry/Pastemask Top")
		(15 "B.Paste" user "Package Geometry/Pastemask Bottom")
		(5 "F.SilkS" user "Ref Des/Silkscreen Top")
		(7 "B.SilkS" user "Ref Des/Silkscreen Bottom")
		(1 "F.Mask" user "Board Geometry/Soldermask Top")
		(3 "B.Mask" user "Board Geometry/Soldermask Bottom")
		(17 "Dwgs.User" user "User.Drawings")
		(19 "Cmts.User" user "User.Comments")
		(21 "Eco1.User" user "User.Eco1")
		(23 "Eco2.User" user "User.Eco2")
		(25 "Edge.Cuts" user "Board Geometry/Outline")
		(27 "Margin" user)
		(31 "F.CrtYd" user "Package Geometry/Place Bound Top")
		(29 "B.CrtYd" user "Package Geometry/Place Bound Bottom")
		(35 "F.Fab" user "Ref Des/Assembly Top")
		(33 "B.Fab" user "Ref Des/Assembly Bottom")
	)
	(footprint ""
		(layer "F.Cu")
		(at 209.172556 -34.772092 90)
		(property "Reference" "U265"
			(at 3.273806 -3.826256 0)
			(unlocked yes)
			(layer "F.SilkS")
			(effects
				(font
					(size 0.7874 0.5842)
					(thickness 0.1524)
				)
			)
		)
		(property "Value" ""
			(at 0 0 90)
			(layer "F.Fab")
			(effects
				(font
					(size 1.27 1.27)
				)
			)
		)
		(duplicate_pad_numbers_are_jumpers no)
		(fp_line
			(start 1.500124 -1.500124)
			(end 1.500124 -1.004062)
			(stroke
				(width 0.1524)
				(type default)
			)
			(layer "F.SilkS")
		)
		(fp_line
			(start 1.004062 -1.500124)
			(end 1.500124 -1.500124)
			(stroke
				(width 0.1524)
				(type default)
			)
			(layer "F.SilkS")
		)
		(fp_line
			(start -1.500124 -1.500124)
			(end -1.004062 -1.500124)
			(stroke
				(width 0.1524)
				(type default)
			)
			(layer "F.SilkS")
		)
		(fp_line
			(start -1.500124 -1.004062)
			(end -1.500124 -1.500124)
			(stroke
				(width 0.1524)
				(type default)
			)
			(layer "F.SilkS")
		)
		(fp_line
			(start 1.500124 1.004062)
			(end 1.500124 1.500124)
			(stroke
				(width 0.1524)
				(type default)
			)
			(layer "F.SilkS")
		)
		(fp_line
			(start 1.500124 1.500124)
			(end 1.004062 1.500124)
			(stroke
				(width 0.1524)
				(type default)
			)
			(layer "F.SilkS")
		)
		(fp_line
			(start -1.004062 1.500124)
			(end -1.500124 1.500124)
			(stroke
				(width 0.1524)
				(type default)
			)
			(layer "F.SilkS")
		)
		(fp_line
			(start -1.500124 1.500124)
			(end -1.500124 1.004062)
			(stroke
				(width 0.1524)
				(type default)
			)
			(layer "F.SilkS")
		)
		(fp_poly
			(pts
				(xy -2.868422 -1.547368) (xy -2.15011 -2.265934) (xy -1.790954 -1.188212)
			)
			(stroke
				(width 0)
				(type default)
			)
			(fill yes)
			(layer "F.SilkS")
		)
		(fp_line
			(start 1.500124 -1.500124)
			(end 1.500124 1.500124)
			(stroke
				(width 0.1)
				(type default)
			)
			(layer "F.Fab")
		)
		(fp_line
			(start -1.500124 -1.500124)
			(end 1.500124 -1.500124)
			(stroke
				(width 0.1)
				(type default)
			)
			(layer "F.Fab")
		)
		(fp_line
			(start 1.500124 1.500124)
			(end -1.500124 1.500124)
			(stroke
				(width 0.1)
				(type default)
			)
			(layer "F.Fab")
		)
		(fp_line
			(start -1.500124 1.500124)
			(end -1.500124 -1.500124)
			(stroke
				(width 0.1)
				(type default)
			)
			(layer "F.Fab")
		)
		(fp_poly
			(pts
				(xy -2.847848 -1.258062) (xy -2.847848 -0.242062) (xy -1.831848 -0.750062)
			)
			(stroke
				(width 0)
				(type default)
			)
			(fill yes)
			(layer "F.Fab")
		)
		(pad "1" smd rect
			(at -1.400048 -0.750062)
			(size 0.2286 0.6096)
			(layers "F.Cu" "F.Mask" "F.Paste")
			(net "INA230_5_A1")
		)
		(pad "2" smd rect
			(at -1.400048 -0.249936)
			(size 0.2286 0.6096)
			(layers "F.Cu" "F.Mask" "F.Paste")
			(net "INA230_5_A0")
		)
		(pad "3" smd rect
			(at -1.400048 0.249936)
			(size 0.2286 0.6096)
			(layers "F.Cu" "F.Mask" "F.Paste")
			(net "P12V_SCM_ADC_ALERT_R")
		)
		(pad "4" smd rect
			(at -1.400048 0.750062)
			(size 0.2286 0.6096)
			(layers "F.Cu" "F.Mask" "F.Paste")
			(net "SMB_INA230_5_3V3AUX_SDA_R1")
		)
		(pad "5" smd rect
			(at -0.750062 1.400048 90)
			(size 0.2286 0.6096)
			(layers "F.Cu" "F.Mask" "F.Paste")
			(net "SMB_INA230_5_3V3AUX_SCL_R1")
		)
		(pad "6" smd rect
			(at -0.249936 1.400048 90)
			(size 0.2286 0.6096)
			(layers "F.Cu" "F.Mask" "F.Paste")
			(net "NC_INA230_5_NC0")
		)
		(pad "7" smd rect
			(at 0.249936 1.400048 90)
			(size 0.2286 0.6096)
			(layers "F.Cu" "F.Mask" "F.Paste")
			(net "NC_INA230_5_NC1")
		)
		(pad "8" smd rect
			(at 0.750062 1.400048 90)
			(size 0.2286 0.6096)
			(layers "F.Cu" "F.Mask" "F.Paste")
			(net "NC_INA230_5_NC2")
		)
		(pad "9" smd rect
			(at 1.400048 0.750062)
			(size 0.2286 0.6096)
			(layers "F.Cu" "F.Mask" "F.Paste")
			(net "P3V3_AUX")
		)
		(pad "10" smd rect
			(at 1.400048 0.249936)
			(size 0.2286 0.6096)
			(layers "F.Cu" "F.Mask" "F.Paste")
			(net "GND")
		)
		(pad "11" smd rect
			(at 1.400048 -0.249936)
			(size 0.2286 0.6096)
			(layers "F.Cu" "F.Mask" "F.Paste")
			(net "P12V_SCM_R")
		)
		(pad "12" smd rect
			(at 1.400048 -0.750062)
			(size 0.2286 0.6096)
			(layers "F.Cu" "F.Mask" "F.Paste")
			(net "VSENSE_P12V_INA230_5_INN")
		)
		(pad "13" smd rect
			(at 0.750062 -1.400048 90)
			(size 0.2286 0.6096)
			(layers "F.Cu" "F.Mask" "F.Paste")
			(net "VSENSE_P12V_INA230_5_INP")
		)
		(pad "14" smd rect
			(at 0.249936 -1.400048 90)
			(size 0.2286 0.6096)
			(layers "F.Cu" "F.Mask" "F.Paste")
			(net "NC_INA230_5_NC3")
		)
		(pad "15" smd rect
			(at -0.249936 -1.400048 90)
			(size 0.2286 0.6096)
			(layers "F.Cu" "F.Mask" "F.Paste")
			(net "NC_INA230_5_NC4")
		)
		(pad "16" smd rect
			(at -0.750062 -1.400048 90)
			(size 0.2286 0.6096)
			(layers "F.Cu" "F.Mask" "F.Paste")
			(net "NC_INA230_5_NC5")
		)
		(pad "TH" smd rect
			(at 0 0 90)
			(size 1.7018 1.7018)
			(layers "F.Cu" "F.Mask" "F.Paste")
			(net "GND")
		)
		(zone
			(layer "F.Cu")
			(hatch none 0.5)
			(connect_pads
				(clearance 0)
			)
			(min_thickness 0.25)
			(keepout
				(tracks not_allowed)
				(vias allowed)
				(pads allowed)
				(copperpour not_allowed)
				(footprints allowed)
			)
			(placement
				(enabled no)
				(sheetname "")
			)
			(fill
				(thermal_gap 0.5)
				(thermal_bridge_width 0.5)
				(island_removal_mode 0)
			)
			(polygon
				(pts
					(xy 209.147156 -33.727644) (xy 208.128108 -33.727644) (xy 208.128108 -35.81654) (xy 210.217004 -35.81654)
					(xy 210.217004 -33.727644) (xy 209.172556 -33.727644) (xy 209.172556 -33.870392) (xy 210.074256 -33.870392)
					(xy 210.074256 -35.673792) (xy 208.270856 -35.673792) (xy 208.270856 -33.870392) (xy 209.147156 -33.870392)
				)
			)
		)
	)
)
